# S9S_MB_2U (Grand Teton) — schematic netlist excerpt (pin names and nets, part order shuffled) for the footprints in the layout excerpt that follows; sources: Cadence DE-HDL packaged netlist, KiCad conversion of 03242023_DA0F0TMBIJ0_F0T_Motherboard_J_brd_V01_OCP.brd

C1988  Q_CAP  1000PF 50V 5% EMPTY  pkg 0402  page 147 : A = GPU_FPGA_EROT_FATALERR_ISO_N ; B = GND
C298  Q_CAP  22UF 4V 20% X6S  pkg C0402  page 77 : A = PVCCIN_CPU1 ; B = GND

(kicad_pcb
	(version 20260206)
	(generator "pcbnew")
	(generator_version "10.0")
	(general
		(thickness 1.6)
		(legacy_teardrops no)
	)
	(paper "A4")
	(title_block
		(title "03242023_DA0F0TMBIJ0_F0T_Motherboard_J_brd_V01_OCP.brd")
		(comment 1 "Grand Teton / footprints 1083-1084 of 6105")
	)
	(layers
		(0 "F.Cu" signal "TOP")
		(4 "In1.Cu" signal "GND")
		(6 "In2.Cu" signal "IN1")
		(8 "In3.Cu" signal "GND1")
		(10 "In4.Cu" signal "IN2")
		(12 "In5.Cu" signal "GND2")
		(14 "In6.Cu" signal "IN3")
		(16 "In7.Cu" signal "GND3")
		(18 "In8.Cu" signal "VCC")
		(20 "In9.Cu" signal "VCC1")
		(22 "In10.Cu" signal "GND4")
		(24 "In11.Cu" signal "IN4")
		(26 "In12.Cu" signal "GND5")
		(28 "In13.Cu" signal "IN5")
		(30 "In14.Cu" signal "GND6")
		(32 "In15.Cu" signal "IN6")
		(34 "In16.Cu" signal "GND7")
		(2 "B.Cu" signal "BOTTOM")
		(9 "F.Adhes" user "F.Adhesive")
		(11 "B.Adhes" user "B.Adhesive")
		(13 "F.Paste" user "Package Geometry/Pastemask Top")
		(15 "B.Paste" user "Package Geometry/Pastemask Bottom")
		(5 "F.SilkS" user "Ref Des/Silkscreen Top")
		(7 "B.SilkS" user "Ref Des/Silkscreen Bottom")
		(1 "F.Mask" user "Board Geometry/Soldermask Top")
		(3 "B.Mask" user "Board Geometry/Soldermask Bottom")
		(17 "Dwgs.User" user "User.Drawings")
		(19 "Cmts.User" user "User.Comments")
		(21 "Eco1.User" user "User.Eco1")
		(23 "Eco2.User" user "User.Eco2")
		(25 "Edge.Cuts" user "Board Geometry/Outline")
		(27 "Margin" user)
		(31 "F.CrtYd" user "Package Geometry/Place Bound Top")
		(29 "B.CrtYd" user "Package Geometry/Place Bound Bottom")
		(35 "F.Fab" user "Ref Des/Assembly Top")
		(33 "B.Fab" user "Ref Des/Assembly Bottom")
	)
	(footprint ""
		(layer "F.Cu")
		(at 116.561616 -244.032024 90)
		(property "Reference" "C298"
			(at 0 0 90)
			(layer "F.SilkS")
			(hide yes)
			(effects
				(font
					(size 1.27 1.27)
				)
			)
		)
		(property "Value" ""
			(at 0 0 90)
			(layer "F.Fab")
			(effects
				(font
					(size 1.27 1.27)
				)
			)
		)
		(duplicate_pad_numbers_are_jumpers no)
		(fp_line
			(start 0.7874 -0.4064)
			(end 0.7874 0.4064)
			(stroke
				(width 0.1524)
				(type default)
			)
			(layer "F.SilkS")
		)
		(fp_line
			(start -0.7874 -0.4064)
			(end 0.7874 -0.4064)
			(stroke
				(width 0.1524)
				(type default)
			)
			(layer "F.SilkS")
		)
		(fp_line
			(start 0.7874 0.4064)
			(end -0.7874 0.4064)
			(stroke
				(width 0.1524)
				(type default)
			)
			(layer "F.SilkS")
		)
		(fp_line
			(start -0.7874 0.4064)
			(end -0.7874 -0.4064)
			(stroke
				(width 0.1524)
				(type default)
			)
			(layer "F.SilkS")
		)
		(fp_line
			(start -0.12065 -0.305054)
			(end -0.12065 -0.2794)
			(stroke
				(width 0.1)
				(type default)
			)
			(layer "F.Fab")
		)
		(fp_line
			(start -0.67945 -0.305054)
			(end -0.12065 -0.305054)
			(stroke
				(width 0.1)
				(type default)
			)
			(layer "F.Fab")
		)
		(fp_line
			(start 0.67945 -0.3048)
			(end 0.67945 0.3048)
			(stroke
				(width 0.1)
				(type default)
			)
			(layer "F.Fab")
		)
		(fp_line
			(start 0.12065 -0.3048)
			(end 0.67945 -0.3048)
			(stroke
				(width 0.1)
				(type default)
			)
			(layer "F.Fab")
		)
		(fp_line
			(start 0.12065 -0.2794)
			(end 0.12065 -0.3048)
			(stroke
				(width 0.1)
				(type default)
			)
			(layer "F.Fab")
		)
		(fp_line
			(start -0.12065 -0.2794)
			(end 0.12065 -0.2794)
			(stroke
				(width 0.1)
				(type default)
			)
			(layer "F.Fab")
		)
		(fp_line
			(start 0.120396 0.2794)
			(end -0.12065 0.2794)
			(stroke
				(width 0.1)
				(type default)
			)
			(layer "F.Fab")
		)
		(fp_line
			(start -0.12065 0.2794)
			(end -0.12065 0.3048)
			(stroke
				(width 0.1)
				(type default)
			)
			(layer "F.Fab")
		)
		(fp_line
			(start 0.67945 0.3048)
			(end 0.120396 0.3048)
			(stroke
				(width 0.1)
				(type default)
			)
			(layer "F.Fab")
		)
		(fp_line
			(start 0.120396 0.3048)
			(end 0.120396 0.2794)
			(stroke
				(width 0.1)
				(type default)
			)
			(layer "F.Fab")
		)
		(fp_line
			(start -0.12065 0.3048)
			(end -0.67945 0.3048)
			(stroke
				(width 0.1)
				(type default)
			)
			(layer "F.Fab")
		)
		(fp_line
			(start -0.67945 0.3048)
			(end -0.67945 -0.305054)
			(stroke
				(width 0.1)
				(type default)
			)
			(layer "F.Fab")
		)
		(pad "1" smd circle
			(at -0.40005 0 90)
			(size 0 0)
			(layers "F.Cu" "F.Mask" "F.Paste")
			(net "PVCCIN_CPU1")
		)
		(pad "2" smd circle
			(at 0.40005 0 90)
			(size 0 0)
			(layers "F.Cu" "F.Mask" "F.Paste")
			(net "GND")
		)
	)
	(footprint ""
		(layer "F.Cu")
		(at 24.069802 -409.402534 180)
		(property "Reference" "C1988"
			(at 0 0 180)
			(layer "F.SilkS")
			(hide yes)
			(effects
				(font
					(size 1.27 1.27)
				)
			)
		)
		(property "Value" ""
			(at 0 0 180)
			(layer "F.Fab")
			(effects
				(font
					(size 1.27 1.27)
				)
			)
		)
		(duplicate_pad_numbers_are_jumpers no)
		(fp_line
			(start 0.7874 0.4064)
			(end -0.7874 0.4064)
			(stroke
				(width 0.1524)
				(type default)
			)
			(layer "F.SilkS")
		)
		(fp_line
			(start 0.7874 -0.4064)
			(end 0.7874 0.4064)
			(stroke
				(width 0.1524)
				(type default)
			)
			(layer "F.SilkS")
		)
		(fp_line
			(start -0.7874 0.4064)
			(end -0.7874 -0.4064)
			(stroke
				(width 0.1524)
				(type default)
			)
			(layer "F.SilkS")
		)
		(fp_line
			(start -0.7874 -0.4064)
			(end 0.7874 -0.4064)
			(stroke
				(width 0.1524)
				(type default)
			)
			(layer "F.SilkS")
		)
		(fp_line
			(start 0.67945 0.3048)
			(end 0.120396 0.3048)
			(stroke
				(width 0.1)
				(type default)
			)
			(layer "F.Fab")
		)
		(fp_line
			(start 0.67945 -0.3048)
			(end 0.67945 0.3048)
			(stroke
				(width 0.1)
				(type default)
			)
			(layer "F.Fab")
		)
		(fp_line
			(start 0.12065 -0.2794)
			(end 0.12065 -0.3048)
			(stroke
				(width 0.1)
				(type default)
			)
			(layer "F.Fab")
		)
		(fp_line
			(start 0.12065 -0.3048)
			(end 0.67945 -0.3048)
			(stroke
				(width 0.1)
				(type default)
			)
			(layer "F.Fab")
		)
		(fp_line
			(start 0.120396 0.3048)
			(end 0.120396 0.2794)
			(stroke
				(width 0.1)
				(type default)
			)
			(layer "F.Fab")
		)
		(fp_line
			(start 0.120396 0.2794)
			(end -0.12065 0.2794)
			(stroke
				(width 0.1)
				(type default)
			)
			(layer "F.Fab")
		)
		(fp_line
			(start -0.12065 0.3048)
			(end -0.67945 0.3048)
			(stroke
				(width 0.1)
				(type default)
			)
			(layer "F.Fab")
		)
		(fp_line
			(start -0.12065 0.2794)
			(end -0.12065 0.3048)
			(stroke
				(width 0.1)
				(type default)
			)
			(layer "F.Fab")
		)
		(fp_line
			(start -0.12065 -0.2794)
			(end 0.12065 -0.2794)
			(stroke
				(width 0.1)
				(type default)
			)
			(layer "F.Fab")
		)
		(fp_line
			(start -0.12065 -0.305054)
			(end -0.12065 -0.2794)
			(stroke
				(width 0.1)
				(type default)
			)
			(layer "F.Fab")
		)
		(fp_line
			(start -0.67945 0.3048)
			(end -0.67945 -0.305054)
			(stroke
				(width 0.1)
				(type default)
			)
			(layer "F.Fab")
		)
		(fp_line
			(start -0.67945 -0.305054)
			(end -0.12065 -0.305054)
			(stroke
				(width 0.1)
				(type default)
			)
			(layer "F.Fab")
		)
		(pad "1" smd circle
			(at -0.40005 0 180)
			(size 0 0)
			(layers "F.Cu" "F.Mask" "F.Paste")
			(net "GPU_FPGA_EROT_FATALERR_ISO_N")
		)
		(pad "2" smd circle
			(at 0.40005 0 180)
			(size 0 0)
			(layers "F.Cu" "F.Mask" "F.Paste")
			(net "GND")
		)
	)
)
